# T6G (Grand Teton) — schematic netlist excerpt (pin names and nets, part order shuffled) for the footprints in the layout excerpt that follows; sources: Cadence DE-HDL packaged netlist, KiCad conversion of 04192023_DAF0TMB3IC0_F0TG_MB_C_brd_V02_OCP.brd

R6005  Q_RES  0 5% CHIP  pkg 0402LF  page 150 : A = I3C_SCM_2_SDA ; B = I3C_SCM_2_R_SDA
PC867  Q_CAP  22UF 4V 20% X6S  pkg C0805  page 269 : A = P1V8_AUX ; B = GND
C2531  Q_CAP  22UF 4V 20% X6S  pkg C0402  page 70 : A = PVDDCR_SOC_P0 ; B = GND

(kicad_pcb
	(version 20260206)
	(generator "pcbnew")
	(generator_version "10.0")
	(general
		(thickness 1.6)
		(legacy_teardrops no)
	)
	(paper "A4")
	(title_block
		(title "04192023_DAF0TMB3IC0_F0TG_MB_C_brd_V02_OCP.brd")
		(comment 1 "Grand Teton / footprints 7946-7948 of 8354")
	)
	(layers
		(0 "F.Cu" signal "TOP")
		(4 "In1.Cu" signal "GND")
		(6 "In2.Cu" signal "IN1")
		(8 "In3.Cu" signal "GND1")
		(10 "In4.Cu" signal "IN2")
		(12 "In5.Cu" signal "GND2")
		(14 "In6.Cu" signal "IN3")
		(16 "In7.Cu" signal "GND3")
		(18 "In8.Cu" signal "VCC")
		(20 "In9.Cu" signal "VCC1")
		(22 "In10.Cu" signal "GND4")
		(24 "In11.Cu" signal "IN4")
		(26 "In12.Cu" signal "GND5")
		(28 "In13.Cu" signal "IN5")
		(30 "In14.Cu" signal "GND6")
		(32 "In15.Cu" signal "IN6")
		(34 "In16.Cu" signal "GND7")
		(2 "B.Cu" signal "BOTTOM")
		(9 "F.Adhes" user "F.Adhesive")
		(11 "B.Adhes" user "B.Adhesive")
		(13 "F.Paste" user "Package Geometry/Pastemask Top")
		(15 "B.Paste" user "Package Geometry/Pastemask Bottom")
		(5 "F.SilkS" user "Ref Des/Silkscreen Top")
		(7 "B.SilkS" user "Ref Des/Silkscreen Bottom")
		(1 "F.Mask" user "Board Geometry/Soldermask Top")
		(3 "B.Mask" user "Board Geometry/Soldermask Bottom")
		(17 "Dwgs.User" user "User.Drawings")
		(19 "Cmts.User" user "User.Comments")
		(21 "Eco1.User" user "User.Eco1")
		(23 "Eco2.User" user "User.Eco2")
		(25 "Edge.Cuts" user "Board Geometry/Outline")
		(27 "Margin" user)
		(31 "F.CrtYd" user "Package Geometry/Place Bound Top")
		(29 "B.CrtYd" user "Package Geometry/Place Bound Bottom")
		(35 "F.Fab" user "Ref Des/Assembly Top")
		(33 "B.Fab" user "Ref Des/Assembly Bottom")
	)
	(footprint ""
		(layer "B.Cu")
		(at 185.240676 -13.60043 -90)
		(property "Reference" "R6005"
			(at 0 0 90)
			(layer "B.SilkS")
			(hide yes)
			(effects
				(font
					(size 1.27 1.27)
				)
				(justify mirror)
			)
		)
		(property "Value" ""
			(at 0 0 90)
			(layer "B.Fab")
			(effects
				(font
					(size 1.27 1.27)
				)
				(justify mirror)
			)
		)
		(duplicate_pad_numbers_are_jumpers no)
		(fp_line
			(start -0.7874 0.4064)
			(end 0.7874 0.4064)
			(stroke
				(width 0.1524)
				(type default)
			)
			(layer "B.SilkS")
		)
		(fp_line
			(start 0.7874 0.4064)
			(end 0.7874 -0.4064)
			(stroke
				(width 0.1524)
				(type default)
			)
			(layer "B.SilkS")
		)
		(fp_line
			(start -0.7874 -0.4064)
			(end -0.7874 0.4064)
			(stroke
				(width 0.1524)
				(type default)
			)
			(layer "B.SilkS")
		)
		(fp_line
			(start 0.7874 -0.4064)
			(end -0.7874 -0.4064)
			(stroke
				(width 0.1524)
				(type default)
			)
			(layer "B.SilkS")
		)
		(fp_line
			(start -0.67945 0.3048)
			(end -0.120396 0.3048)
			(stroke
				(width 0.1)
				(type default)
			)
			(layer "B.Fab")
		)
		(fp_line
			(start -0.120396 0.3048)
			(end -0.120396 0.2794)
			(stroke
				(width 0.1)
				(type default)
			)
			(layer "B.Fab")
		)
		(fp_line
			(start 0.12065 0.3048)
			(end 0.67945 0.3048)
			(stroke
				(width 0.1)
				(type default)
			)
			(layer "B.Fab")
		)
		(fp_line
			(start 0.67945 0.3048)
			(end 0.67945 -0.305054)
			(stroke
				(width 0.1)
				(type default)
			)
			(layer "B.Fab")
		)
		(fp_line
			(start -0.120396 0.2794)
			(end 0.12065 0.2794)
			(stroke
				(width 0.1)
				(type default)
			)
			(layer "B.Fab")
		)
		(fp_line
			(start 0.12065 0.2794)
			(end 0.12065 0.3048)
			(stroke
				(width 0.1)
				(type default)
			)
			(layer "B.Fab")
		)
		(fp_line
			(start -0.12065 -0.2794)
			(end -0.12065 -0.3048)
			(stroke
				(width 0.1)
				(type default)
			)
			(layer "B.Fab")
		)
		(fp_line
			(start 0.12065 -0.2794)
			(end -0.12065 -0.2794)
			(stroke
				(width 0.1)
				(type default)
			)
			(layer "B.Fab")
		)
		(fp_line
			(start -0.67945 -0.3048)
			(end -0.67945 0.3048)
			(stroke
				(width 0.1)
				(type default)
			)
			(layer "B.Fab")
		)
		(fp_line
			(start -0.12065 -0.3048)
			(end -0.67945 -0.3048)
			(stroke
				(width 0.1)
				(type default)
			)
			(layer "B.Fab")
		)
		(fp_line
			(start 0.12065 -0.305054)
			(end 0.12065 -0.2794)
			(stroke
				(width 0.1)
				(type default)
			)
			(layer "B.Fab")
		)
		(fp_line
			(start 0.67945 -0.305054)
			(end 0.12065 -0.305054)
			(stroke
				(width 0.1)
				(type default)
			)
			(layer "B.Fab")
		)
		(pad "1" smd circle
			(at 0.40005 0 90)
			(size 0 0)
			(layers "B.Cu" "B.Mask" "B.Paste")
			(net "I3C_SCM_2_SDA")
		)
		(pad "2" smd circle
			(at -0.40005 0 90)
			(size 0 0)
			(layers "B.Cu" "B.Mask" "B.Paste")
			(net "I3C_SCM_2_R_SDA")
		)
	)
	(footprint ""
		(layer "B.Cu")
		(at 152.202642 -80.81518)
		(property "Reference" "PC867"
			(at 0 0 0)
			(layer "B.SilkS")
			(hide yes)
			(effects
				(font
					(size 1.27 1.27)
				)
				(justify mirror)
			)
		)
		(property "Value" ""
			(at 0 0 0)
			(layer "B.Fab")
			(effects
				(font
					(size 1.27 1.27)
				)
				(justify mirror)
			)
		)
		(duplicate_pad_numbers_are_jumpers no)
		(fp_line
			(start -1.524 -0.762)
			(end -1.524 0.762)
			(stroke
				(width 0.1524)
				(type default)
			)
			(layer "B.SilkS")
		)
		(fp_line
			(start -1.524 0.762)
			(end 1.524 0.762)
			(stroke
				(width 0.1524)
				(type default)
			)
			(layer "B.SilkS")
		)
		(fp_line
			(start 1.524 -0.762)
			(end -1.524 -0.762)
			(stroke
				(width 0.1524)
				(type default)
			)
			(layer "B.SilkS")
		)
		(fp_line
			(start 1.524 0.762)
			(end 1.524 -0.762)
			(stroke
				(width 0.1524)
				(type default)
			)
			(layer "B.SilkS")
		)
		(fp_line
			(start -1.1049 -0.724916)
			(end 1.1049 -0.724916)
			(stroke
				(width 0.1)
				(type default)
			)
			(layer "B.Fab")
		)
		(fp_line
			(start -1.1049 0.724916)
			(end -1.1049 -0.724916)
			(stroke
				(width 0.1)
				(type default)
			)
			(layer "B.Fab")
		)
		(fp_line
			(start 1.1049 -0.724916)
			(end 1.1049 0.724916)
			(stroke
				(width 0.1)
				(type default)
			)
			(layer "B.Fab")
		)
		(fp_line
			(start 1.1049 0.724916)
			(end -1.1049 0.724916)
			(stroke
				(width 0.1)
				(type default)
			)
			(layer "B.Fab")
		)
		(pad "1" smd rect
			(at 0.889 0)
			(size 1.016 1.27)
			(layers "B.Cu" "B.Mask" "B.Paste")
			(net "P1V8_AUX")
		)
		(pad "2" smd rect
			(at -0.889 0)
			(size 1.016 1.27)
			(layers "B.Cu" "B.Mask" "B.Paste")
			(net "GND")
		)
	)
	(footprint ""
		(layer "B.Cu")
		(at 365.835692 -260.305042)
		(property "Reference" "C2531"
			(at 0 0 0)
			(layer "B.SilkS")
			(hide yes)
			(effects
				(font
					(size 1.27 1.27)
				)
				(justify mirror)
			)
		)
		(property "Value" ""
			(at 0 0 0)
			(layer "B.Fab")
			(effects
				(font
					(size 1.27 1.27)
				)
				(justify mirror)
			)
		)
		(duplicate_pad_numbers_are_jumpers no)
		(fp_line
			(start -0.7874 -0.4064)
			(end -0.7874 0.4064)
			(stroke
				(width 0.1524)
				(type default)
			)
			(layer "B.SilkS")
		)
		(fp_line
			(start -0.7874 0.4064)
			(end 0.7874 0.4064)
			(stroke
				(width 0.1524)
				(type default)
			)
			(layer "B.SilkS")
		)
		(fp_line
			(start 0.7874 -0.4064)
			(end -0.7874 -0.4064)
			(stroke
				(width 0.1524)
				(type default)
			)
			(layer "B.SilkS")
		)
		(fp_line
			(start 0.7874 0.4064)
			(end 0.7874 -0.4064)
			(stroke
				(width 0.1524)
				(type default)
			)
			(layer "B.SilkS")
		)
		(fp_line
			(start -0.67945 -0.3048)
			(end -0.67945 0.3048)
			(stroke
				(width 0.1)
				(type default)
			)
			(layer "B.Fab")
		)
		(fp_line
			(start -0.67945 0.3048)
			(end -0.120396 0.3048)
			(stroke
				(width 0.1)
				(type default)
			)
			(layer "B.Fab")
		)
		(fp_line
			(start -0.12065 -0.3048)
			(end -0.67945 -0.3048)
			(stroke
				(width 0.1)
				(type default)
			)
			(layer "B.Fab")
		)
		(fp_line
			(start -0.12065 -0.2794)
			(end -0.12065 -0.3048)
			(stroke
				(width 0.1)
				(type default)
			)
			(layer "B.Fab")
		)
		(fp_line
			(start -0.120396 0.2794)
			(end 0.12065 0.2794)
			(stroke
				(width 0.1)
				(type default)
			)
			(layer "B.Fab")
		)
		(fp_line
			(start -0.120396 0.3048)
			(end -0.120396 0.2794)
			(stroke
				(width 0.1)
				(type default)
			)
			(layer "B.Fab")
		)
		(fp_line
			(start 0.12065 -0.305054)
			(end 0.12065 -0.2794)
			(stroke
				(width 0.1)
				(type default)
			)
			(layer "B.Fab")
		)
		(fp_line
			(start 0.12065 -0.2794)
			(end -0.12065 -0.2794)
			(stroke
				(width 0.1)
				(type default)
			)
			(layer "B.Fab")
		)
		(fp_line
			(start 0.12065 0.2794)
			(end 0.12065 0.3048)
			(stroke
				(width 0.1)
				(type default)
			)
			(layer "B.Fab")
		)
		(fp_line
			(start 0.12065 0.3048)
			(end 0.67945 0.3048)
			(stroke
				(width 0.1)
				(type default)
			)
			(layer "B.Fab")
		)
		(fp_line
			(start 0.67945 -0.305054)
			(end 0.12065 -0.305054)
			(stroke
				(width 0.1)
				(type default)
			)
			(layer "B.Fab")
		)
		(fp_line
			(start 0.67945 0.3048)
			(end 0.67945 -0.305054)
			(stroke
				(width 0.1)
				(type default)
			)
			(layer "B.Fab")
		)
		(pad "1" smd circle
			(at 0.40005 0 180)
			(size 0 0)
			(layers "B.Cu" "B.Mask" "B.Paste")
			(net "PVDDCR_SOC_P0")
		)
		(pad "2" smd circle
			(at -0.40005 0 180)
			(size 0 0)
			(layers "B.Cu" "B.Mask" "B.Paste")
			(net "GND")
		)
	)
)
